(kicad_pcb
	(version 20260206)
	(generator "pcbnew")
	(generator_version "10.0")
	(general
		(thickness 1.6)
		(legacy_teardrops no)
	)
	(paper "A4")
	(title_block
		(title "timecard-production-celestica-r4006 — R4006-B0001-02_R01.brd")
		(comment 1 "Time Appliance Project (Time Card) / footprints 1044-1048 of 1113")
	)
	(layers
		(0 "F.Cu" signal "TOP")
		(4 "In1.Cu" signal "L02_GND1")
		(6 "In2.Cu" signal "L03_SIG1")
		(8 "In3.Cu" signal "L04_GND2")
		(10 "In4.Cu" signal "L05_VCC1")
		(12 "In5.Cu" signal "L06_VCC2")
		(14 "In6.Cu" signal "L07_GND3")
		(16 "In7.Cu" signal "L08_SIG2")
		(18 "In8.Cu" signal "L09_GND4")
		(2 "B.Cu" signal "BOTTOM")
		(9 "F.Adhes" user "F.Adhesive")
		(11 "B.Adhes" user "B.Adhesive")
		(13 "F.Paste" user "Package Geometry/Pastemask Top")
		(15 "B.Paste" user "Package Geometry/Pastemask Bottom")
		(5 "F.SilkS" user "Ref Des/Silkscreen Top")
		(7 "B.SilkS" user "Ref Des/Silkscreen Bottom")
		(1 "F.Mask" user "Board Geometry/Soldermask Top")
		(3 "B.Mask" user "Board Geometry/Soldermask Bottom")
		(17 "Dwgs.User" user "User.Drawings")
		(19 "Cmts.User" user "User.Comments")
		(21 "Eco1.User" user "User.Eco1")
		(23 "Eco2.User" user "User.Eco2")
		(25 "Edge.Cuts" user "Board Geometry/Outline")
		(27 "Margin" user)
		(31 "F.CrtYd" user "Package Geometry/Place Bound Top")
		(29 "B.CrtYd" user "Package Geometry/Place Bound Bottom")
		(35 "F.Fab" user "Ref Des/Assembly Top")
		(33 "B.Fab" user "Ref Des/Assembly Bottom")
	)
	(footprint ""
		(layer "B.Cu")
		(at 90.424 -104.902)
		(property "Reference" "R51"
			(at 0.127 -2.88163 0)
			(unlocked yes)
			(layer "B.SilkS")
			(effects
				(font
					(size 0.7874 0.5842)
					(thickness 0.1524)
				)
				(justify mirror)
			)
		)
		(property "Value" "VAL*"
			(at -0.02032 2.13233 0)
			(unlocked yes)
			(layer "B.Fab")
			(hide yes)
			(effects
				(font
					(size 0.7874 0.5842)
					(thickness 0.1524)
				)
				(justify mirror)
			)
		)
		(property "Tolerance" "TOL*"
			(at -0.044704 3.05435 0)
			(unlocked yes)
			(layer "Cmts.User")
			(hide yes)
			(effects
				(font
					(size 0.7874 0.5842)
					(thickness 0.1524)
				)
				(justify mirror)
			)
		)
		(property "User Part Number" "PARTNUM*"
			(at -0.02032 4.024884 0)
			(unlocked yes)
			(layer "Cmts.User")
			(hide yes)
			(effects
				(font
					(size 0.7874 0.5842)
					(thickness 0.1524)
				)
				(justify mirror)
			)
		)
		(property "Device Type" "RESISTOR-G155-11002-01,10KOHM,A"
			(at -0.008382 1.210564 0)
			(unlocked yes)
			(layer "B.Fab")
			(hide yes)
			(effects
				(font
					(size 0.7874 0.5842)
					(thickness 0.1524)
				)
				(justify mirror)
			)
		)
		(duplicate_pad_numbers_are_jumpers no)
		(fp_line
			(start -1.143 -0.5588)
			(end 1.143 -0.5588)
			(stroke
				(width 0.1)
				(type default)
			)
			(layer "B.SilkS")
		)
		(fp_line
			(start -1.143 0.5588)
			(end -1.143 -0.5588)
			(stroke
				(width 0.1)
				(type default)
			)
			(layer "B.SilkS")
		)
		(fp_line
			(start 1.143 -0.5588)
			(end 1.143 0.5588)
			(stroke
				(width 0.1)
				(type default)
			)
			(layer "B.SilkS")
		)
		(fp_line
			(start 1.143 0.5588)
			(end -1.143 0.5588)
			(stroke
				(width 0.1)
				(type default)
			)
			(layer "B.SilkS")
		)
		(fp_poly
			(pts
				(xy 1.143 0.5588) (xy -1.143 0.5588) (xy -1.143 -0.5588) (xy 1.143 -0.5588)
			)
			(stroke
				(width 0)
				(type default)
			)
			(fill no)
			(layer "B.CrtYd")
		)
		(fp_line
			(start -0.508 -0.3048)
			(end 0.508 -0.3048)
			(stroke
				(width 0.1)
				(type default)
			)
			(layer "B.Fab")
		)
		(fp_line
			(start -0.508 0.3048)
			(end -0.508 -0.3048)
			(stroke
				(width 0.1)
				(type default)
			)
			(layer "B.Fab")
		)
		(fp_line
			(start 0.508 -0.3048)
			(end 0.508 0.3048)
			(stroke
				(width 0.1)
				(type default)
			)
			(layer "B.Fab")
		)
		(fp_line
			(start 0.508 0.3048)
			(end -0.508 0.3048)
			(stroke
				(width 0.1)
				(type default)
			)
			(layer "B.Fab")
		)
		(pad "1" smd rect
			(at 0.5334 0 180)
			(size 0.7112 0.6096)
			(layers "B.Cu" "B.Mask" "B.Paste")
			(net "XP3R3V")
		)
		(pad "2" smd rect
			(at -0.5334 0 180)
			(size 0.7112 0.6096)
			(layers "B.Cu" "B.Mask" "B.Paste")
			(net "R_XP3R3V_PG")
		)
		(zone
			(layer "B.Cu")
			(hatch none 0.5)
			(connect_pads
				(clearance 0)
			)
			(min_thickness 0.25)
			(keepout
				(tracks allowed)
				(vias not_allowed)
				(pads allowed)
				(copperpour not_allowed)
				(footprints allowed)
			)
			(placement
				(enabled no)
				(sheetname "")
			)
			(fill
				(thermal_gap 0.5)
				(thermal_bridge_width 0.5)
				(island_removal_mode 0)
			)
			(polygon
				(pts
					(xy 90.5002 -104.5972) (xy 90.5002 -105.2068) (xy 90.3478 -105.2068) (xy 90.3478 -104.5972)
				)
			)
		)
		(zone
			(layer "B.Cu")
			(hatch none 0.5)
			(connect_pads
				(clearance 0)
			)
			(min_thickness 0.25)
			(keepout
				(tracks not_allowed)
				(vias allowed)
				(pads allowed)
				(copperpour not_allowed)
				(footprints allowed)
			)
			(placement
				(enabled no)
				(sheetname "")
			)
			(fill
				(thermal_gap 0.5)
				(thermal_bridge_width 0.5)
				(island_removal_mode 0)
			)
			(polygon
				(pts
					(xy 90.5002 -104.5972) (xy 90.5002 -105.2068) (xy 90.3478 -105.2068) (xy 90.3478 -104.5972)
				)
			)
		)
	)
	(footprint ""
		(layer "B.Cu")
		(at 110.847124 -37.323268 -90)
		(property "Reference" "C220"
			(at 1.382268 42.044874 270)
			(unlocked yes)
			(layer "B.SilkS")
			(effects
				(font
					(size 0.635 0.4064)
					(thickness 0.1524)
				)
				(justify mirror)
			)
		)
		(property "Value" "VAL*"
			(at 0 3.718306 270)
			(unlocked yes)
			(layer "B.Fab")
			(hide yes)
			(effects
				(font
					(size 0.7874 0.5842)
					(thickness 0.127)
				)
				(justify mirror)
			)
		)
		(property "Tolerance" "TOL*"
			(at 0 4.861306 270)
			(unlocked yes)
			(layer "Cmts.User")
			(hide yes)
			(effects
				(font
					(size 0.7874 0.5842)
					(thickness 0.127)
				)
				(justify mirror)
			)
		)
		(property "User Part Number" "PARTNUM*"
			(at 0 2.575306 270)
			(unlocked yes)
			(layer "Cmts.User")
			(hide yes)
			(effects
				(font
					(size 0.7874 0.5842)
					(thickness 0.127)
				)
				(justify mirror)
			)
		)
		(property "Device Type" "CAPACITOR-G105-0B104-CK,0.1UF,A"
			(at 0 1.432306 270)
			(unlocked yes)
			(layer "B.Fab")
			(hide yes)
			(effects
				(font
					(size 0.7874 0.5842)
					(thickness 0.127)
				)
				(justify mirror)
			)
		)
		(duplicate_pad_numbers_are_jumpers no)
		(fp_line
			(start -0.970026 0.4699)
			(end 0.970026 0.4699)
			(stroke
				(width 0.1)
				(type default)
			)
			(layer "B.SilkS")
		)
		(fp_line
			(start 0.970026 0.4699)
			(end 0.970026 -0.4699)
			(stroke
				(width 0.1)
				(type default)
			)
			(layer "B.SilkS")
		)
		(fp_line
			(start -0.970026 -0.4699)
			(end -0.970026 0.4699)
			(stroke
				(width 0.1)
				(type default)
			)
			(layer "B.SilkS")
		)
		(fp_line
			(start 0.970026 -0.4699)
			(end -0.970026 -0.4699)
			(stroke
				(width 0.1)
				(type default)
			)
			(layer "B.SilkS")
		)
		(fp_poly
			(pts
				(xy 0.970026 0.4699) (xy -0.970026 0.4699) (xy -0.970026 -0.4699) (xy 0.970026 -0.4699)
			)
			(stroke
				(width 0)
				(type default)
			)
			(fill no)
			(layer "B.CrtYd")
		)
		(fp_line
			(start -0.508 0.3048)
			(end 0.508 0.3048)
			(stroke
				(width 0.1)
				(type default)
			)
			(layer "B.Fab")
		)
		(fp_line
			(start 0.508 0.3048)
			(end 0.508 -0.3048)
			(stroke
				(width 0.1)
				(type default)
			)
			(layer "B.Fab")
		)
		(fp_line
			(start -0.508 -0.3048)
			(end -0.508 0.3048)
			(stroke
				(width 0.1)
				(type default)
			)
			(layer "B.Fab")
		)
		(fp_line
			(start 0.508 -0.3048)
			(end -0.508 -0.3048)
			(stroke
				(width 0.1)
				(type default)
			)
			(layer "B.Fab")
		)
		(pad "1" smd circle
			(at 0.500126 0 90)
			(size 0.635 0.635)
			(layers "B.Cu" "B.Mask" "B.Paste")
			(net "XP2R5V_FPGA")
		)
		(pad "2" smd circle
			(at -0.500126 0 90)
			(size 0.635 0.635)
			(layers "B.Cu" "B.Mask" "B.Paste")
			(net "SG")
		)
	)
	(footprint ""
		(layer "B.Cu")
		(at 95.631 -83.312)
		(property "Reference" "R200"
			(at -0.254 -5.54863 0)
			(unlocked yes)
			(layer "B.SilkS")
			(effects
				(font
					(size 0.7874 0.5842)
					(thickness 0.1524)
				)
				(justify mirror)
			)
		)
		(property "Value" "VAL*"
			(at -0.02032 2.13233 0)
			(unlocked yes)
			(layer "B.Fab")
			(hide yes)
			(effects
				(font
					(size 0.7874 0.5842)
					(thickness 0.1524)
				)
				(justify mirror)
			)
		)
		(property "Tolerance" "TOL*"
			(at -0.044704 3.05435 0)
			(unlocked yes)
			(layer "Cmts.User")
			(hide yes)
			(effects
				(font
					(size 0.7874 0.5842)
					(thickness 0.1524)
				)
				(justify mirror)
			)
		)
		(property "User Part Number" "PARTNUM*"
			(at -0.02032 4.024884 0)
			(unlocked yes)
			(layer "Cmts.User")
			(hide yes)
			(effects
				(font
					(size 0.7874 0.5842)
					(thickness 0.1524)
				)
				(justify mirror)
			)
		)
		(property "Device Type" "RESISTOR-G155-14701-01,4.7KOHMA"
			(at -0.008382 1.210564 0)
			(unlocked yes)
			(layer "B.Fab")
			(hide yes)
			(effects
				(font
					(size 0.7874 0.5842)
					(thickness 0.1524)
				)
				(justify mirror)
			)
		)
		(duplicate_pad_numbers_are_jumpers no)
		(fp_line
			(start -1.143 -0.5588)
			(end 1.143 -0.5588)
			(stroke
				(width 0.1)
				(type default)
			)
			(layer "B.SilkS")
		)
		(fp_line
			(start -1.143 0.5588)
			(end -1.143 -0.5588)
			(stroke
				(width 0.1)
				(type default)
			)
			(layer "B.SilkS")
		)
		(fp_line
			(start 1.143 -0.5588)
			(end 1.143 0.5588)
			(stroke
				(width 0.1)
				(type default)
			)
			(layer "B.SilkS")
		)
		(fp_line
			(start 1.143 0.5588)
			(end -1.143 0.5588)
			(stroke
				(width 0.1)
				(type default)
			)
			(layer "B.SilkS")
		)
		(fp_rect
			(start -1.143 0.5588)
			(end 1.143 -0.5588)
			(stroke
				(width 0)
				(type default)
			)
			(fill no)
			(layer "B.CrtYd")
		)
		(fp_line
			(start -0.508 -0.3048)
			(end 0.508 -0.3048)
			(stroke
				(width 0.1)
				(type default)
			)
			(layer "B.Fab")
		)
		(fp_line
			(start -0.508 0.3048)
			(end -0.508 -0.3048)
			(stroke
				(width 0.1)
				(type default)
			)
			(layer "B.Fab")
		)
		(fp_line
			(start 0.508 -0.3048)
			(end 0.508 0.3048)
			(stroke
				(width 0.1)
				(type default)
			)
			(layer "B.Fab")
		)
		(fp_line
			(start 0.508 0.3048)
			(end -0.508 0.3048)
			(stroke
				(width 0.1)
				(type default)
			)
			(layer "B.Fab")
		)
		(pad "1" smd rect
			(at 0.5334 0 180)
			(size 0.7112 0.6096)
			(layers "B.Cu" "B.Mask" "B.Paste")
			(net "UNNAMED_127_MT25QL128ABA1ESES_1")
		)
		(pad "2" smd rect
			(at -0.5334 0 180)
			(size 0.7112 0.6096)
			(layers "B.Cu" "B.Mask" "B.Paste")
			(net "XP3R3V_FPGA")
		)
		(zone
			(layer "B.Cu")
			(hatch none 0.5)
			(connect_pads
				(clearance 0)
			)
			(min_thickness 0.25)
			(keepout
				(tracks allowed)
				(vias not_allowed)
				(pads allowed)
				(copperpour not_allowed)
				(footprints allowed)
			)
			(placement
				(enabled no)
				(sheetname "")
			)
			(fill
				(thermal_gap 0.5)
				(thermal_bridge_width 0.5)
				(island_removal_mode 0)
			)
			(polygon
				(pts
					(xy 95.5548 -83.0072) (xy 95.7072 -83.0072) (xy 95.7072 -83.6168) (xy 95.5548 -83.6168)
				)
			)
		)
	)
	(footprint ""
		(layer "B.Cu")
		(at 33.782 -19.1262 180)
		(property "Reference" "R158"
			(at -3.175 -0.62357 0)
			(unlocked yes)
			(layer "B.SilkS")
			(effects
				(font
					(size 0.7874 0.5842)
					(thickness 0.1524)
				)
				(justify mirror)
			)
		)
		(property "Value" "VAL*"
			(at -0.02032 2.13233 180)
			(unlocked yes)
			(layer "B.Fab")
			(hide yes)
			(effects
				(font
					(size 0.7874 0.5842)
					(thickness 0.1524)
				)
				(justify mirror)
			)
		)
		(property "Device Type" "RESISTOR-G155-14701-01,4.7KOHMA"
			(at -0.008382 1.210564 180)
			(unlocked yes)
			(layer "B.Fab")
			(hide yes)
			(effects
				(font
					(size 0.7874 0.5842)
					(thickness 0.1524)
				)
				(justify mirror)
			)
		)
		(property "User Part Number" "PARTNUM*"
			(at -0.02032 4.024884 180)
			(unlocked yes)
			(layer "Cmts.User")
			(hide yes)
			(effects
				(font
					(size 0.7874 0.5842)
					(thickness 0.1524)
				)
				(justify mirror)
			)
		)
		(property "Tolerance" "TOL*"
			(at -0.044704 3.05435 180)
			(unlocked yes)
			(layer "Cmts.User")
			(hide yes)
			(effects
				(font
					(size 0.7874 0.5842)
					(thickness 0.1524)
				)
				(justify mirror)
			)
		)
		(duplicate_pad_numbers_are_jumpers no)
		(fp_line
			(start 1.143 0.5588)
			(end -1.143 0.5588)
			(stroke
				(width 0.1)
				(type default)
			)
			(layer "B.SilkS")
		)
		(fp_line
			(start 1.143 -0.5588)
			(end 1.143 0.5588)
			(stroke
				(width 0.1)
				(type default)
			)
			(layer "B.SilkS")
		)
		(fp_line
			(start -1.143 0.5588)
			(end -1.143 -0.5588)
			(stroke
				(width 0.1)
				(type default)
			)
			(layer "B.SilkS")
		)
		(fp_line
			(start -1.143 -0.5588)
			(end 1.143 -0.5588)
			(stroke
				(width 0.1)
				(type default)
			)
			(layer "B.SilkS")
		)
		(fp_rect
			(start 1.143 -0.5588)
			(end -1.143 0.5588)
			(stroke
				(width 0)
				(type default)
			)
			(fill no)
			(layer "B.CrtYd")
		)
		(fp_line
			(start 0.508 0.3048)
			(end -0.508 0.3048)
			(stroke
				(width 0.1)
				(type default)
			)
			(layer "B.Fab")
		)
		(fp_line
			(start 0.508 -0.3048)
			(end 0.508 0.3048)
			(stroke
				(width 0.1)
				(type default)
			)
			(layer "B.Fab")
		)
		(fp_line
			(start -0.508 0.3048)
			(end -0.508 -0.3048)
			(stroke
				(width 0.1)
				(type default)
			)
			(layer "B.Fab")
		)
		(fp_line
			(start -0.508 -0.3048)
			(end 0.508 -0.3048)
			(stroke
				(width 0.1)
				(type default)
			)
			(layer "B.Fab")
		)
		(pad "1" smd rect
			(at 0.5334 0)
			(size 0.7112 0.6096)
			(layers "B.Cu" "B.Mask" "B.Paste")
			(net "XP3R3V_FPGA")
		)
		(pad "2" smd rect
			(at -0.5334 0)
			(size 0.7112 0.6096)
			(layers "B.Cu" "B.Mask" "B.Paste")
			(net "UNNAMED_5_24LC16BTISTTSSOP8_I15")
		)
		(zone
			(layer "B.Cu")
			(hatch none 0.5)
			(connect_pads
				(clearance 0)
			)
			(min_thickness 0.25)
			(keepout
				(tracks allowed)
				(vias not_allowed)
				(pads allowed)
				(copperpour not_allowed)
				(footprints allowed)
			)
			(placement
				(enabled no)
				(sheetname "")
			)
			(fill
				(thermal_gap 0.5)
				(thermal_bridge_width 0.5)
				(island_removal_mode 0)
			)
			(polygon
				(pts
					(xy 33.7058 -18.8214) (xy 33.8582 -18.8214) (xy 33.8582 -19.431) (xy 33.7058 -19.431)
				)
			)
		)
	)
	(footprint ""
		(layer "B.Cu")
		(at 64.262 -60.325 180)
		(property "Reference" "R107"
			(at 2.159 1.10363 0)
			(unlocked yes)
			(layer "B.SilkS")
			(effects
				(font
					(size 0.7874 0.5842)
					(thickness 0.1524)
				)
				(justify mirror)
			)
		)
		(property "Value" "VAL*"
			(at -0.02032 2.13233 180)
			(unlocked yes)
			(layer "B.Fab")
			(hide yes)
			(effects
				(font
					(size 0.7874 0.5842)
					(thickness 0.1524)
				)
				(justify mirror)
			)
		)
		(property "Tolerance" "TOL*"
			(at -0.044704 3.05435 180)
			(unlocked yes)
			(layer "Cmts.User")
			(hide yes)
			(effects
				(font
					(size 0.7874 0.5842)
					(thickness 0.1524)
				)
				(justify mirror)
			)
		)
		(property "User Part Number" "PARTNUM*"
			(at -0.02032 4.024884 180)
			(unlocked yes)
			(layer "Cmts.User")
			(hide yes)
			(effects
				(font
					(size 0.7874 0.5842)
					(thickness 0.1524)
				)
				(justify mirror)
			)
		)
		(property "Device Type" "RESISTOR-G155-14701-01,4.7KOHMA"
			(at -0.008382 1.210564 180)
			(unlocked yes)
			(layer "B.Fab")
			(hide yes)
			(effects
				(font
					(size 0.7874 0.5842)
					(thickness 0.1524)
				)
				(justify mirror)
			)
		)
		(duplicate_pad_numbers_are_jumpers no)
		(fp_line
			(start 1.143 0.5588)
			(end -1.143 0.5588)
			(stroke
				(width 0.1)
				(type default)
			)
			(layer "B.SilkS")
		)
		(fp_line
			(start 1.143 -0.5588)
			(end 1.143 0.5588)
			(stroke
				(width 0.1)
				(type default)
			)
			(layer "B.SilkS")
		)
		(fp_line
			(start -1.143 0.5588)
			(end -1.143 -0.5588)
			(stroke
				(width 0.1)
				(type default)
			)
			(layer "B.SilkS")
		)
		(fp_line
			(start -1.143 -0.5588)
			(end 1.143 -0.5588)
			(stroke
				(width 0.1)
				(type default)
			)
			(layer "B.SilkS")
		)
		(fp_rect
			(start -1.143 -0.5588)
			(end 1.143 0.5588)
			(stroke
				(width 0)
				(type default)
			)
			(fill no)
			(layer "B.CrtYd")
		)
		(fp_line
			(start 0.508 0.3048)
			(end -0.508 0.3048)
			(stroke
				(width 0.1)
				(type default)
			)
			(layer "B.Fab")
		)
		(fp_line
			(start 0.508 -0.3048)
			(end 0.508 0.3048)
			(stroke
				(width 0.1)
				(type default)
			)
			(layer "B.Fab")
		)
		(fp_line
			(start -0.508 0.3048)
			(end -0.508 -0.3048)
			(stroke
				(width 0.1)
				(type default)
			)
			(layer "B.Fab")
		)
		(fp_line
			(start -0.508 -0.3048)
			(end 0.508 -0.3048)
			(stroke
				(width 0.1)
				(type default)
			)
			(layer "B.Fab")
		)
		(pad "1" smd rect
			(at 0.5334 0)
			(size 0.7112 0.6096)
			(layers "B.Cu" "B.Mask" "B.Paste")
			(net "XP3R3V_FPGA")
		)
		(pad "2" smd rect
			(at -0.5334 0)
			(size 0.7112 0.6096)
			(layers "B.Cu" "B.Mask" "B.Paste")
			(net "FPGA_IN_MAC_USB_OC_N")
		)
		(zone
			(layer "B.Cu")
			(hatch none 0.5)
			(connect_pads
				(clearance 0)
			)
			(min_thickness 0.25)
			(keepout
				(tracks allowed)
				(vias not_allowed)
				(pads allowed)
				(copperpour not_allowed)
				(footprints allowed)
			)
			(placement
				(enabled no)
				(sheetname "")
			)
			(fill
				(thermal_gap 0.5)
				(thermal_bridge_width 0.5)
				(island_removal_mode 0)
			)
			(polygon
				(pts
					(xy 64.3382 -60.0202) (xy 64.3382 -60.6298) (xy 64.1858 -60.6298) (xy 64.1858 -60.0202)
				)
			)
		)
	)
)
